(kicad_pcb
	(version 20260206)
	(generator "pcbnew")
	(generator_version "10.0")
	(general
		(thickness 1.6)
		(legacy_teardrops no)
	)
	(paper "A4")
	(title_block
		(title "01162023_DA0F0TEBIF0_F0T_Expander_BD_F_brd_V02_OCP.brd")
		(comment 1 "Grand Teton / footprints 3330-3336 of 9728")
	)
	(layers
		(0 "F.Cu" signal "TOP")
		(4 "In1.Cu" signal "GND")
		(6 "In2.Cu" signal "VCC")
		(8 "In3.Cu" signal "VCC1")
		(10 "In4.Cu" signal "GND1")
		(12 "In5.Cu" signal "IN1")
		(14 "In6.Cu" signal "GND2")
		(16 "In7.Cu" signal "IN2")
		(18 "In8.Cu" signal "GND3")
		(20 "In9.Cu" signal "IN3")
		(22 "In10.Cu" signal "GND4")
		(24 "In11.Cu" signal "IN4")
		(26 "In12.Cu" signal "GND5")
		(28 "In13.Cu" signal "IN5")
		(30 "In14.Cu" signal "GND6")
		(32 "In15.Cu" signal "IN6")
		(34 "In16.Cu" signal "GND7")
		(2 "B.Cu" signal "BOTTOM")
		(9 "F.Adhes" user "F.Adhesive")
		(11 "B.Adhes" user "B.Adhesive")
		(13 "F.Paste" user "Package Geometry/Pastemask Top")
		(15 "B.Paste" user "Package Geometry/Pastemask Bottom")
		(5 "F.SilkS" user "Ref Des/Silkscreen Top")
		(7 "B.SilkS" user "Ref Des/Silkscreen Bottom")
		(1 "F.Mask" user "Board Geometry/Soldermask Top")
		(3 "B.Mask" user "Board Geometry/Soldermask Bottom")
		(17 "Dwgs.User" user "User.Drawings")
		(19 "Cmts.User" user "User.Comments")
		(21 "Eco1.User" user "User.Eco1")
		(23 "Eco2.User" user "User.Eco2")
		(25 "Edge.Cuts" user "Board Geometry/Outline")
		(27 "Margin" user)
		(31 "F.CrtYd" user "Package Geometry/Place Bound Top")
		(29 "B.CrtYd" user "Package Geometry/Place Bound Bottom")
		(35 "F.Fab" user "Ref Des/Assembly Top")
		(33 "B.Fab" user "Ref Des/Assembly Bottom")
	)
	(footprint ""
		(layer "F.Cu")
		(at 43.622722 -22.867366 90)
		(property "Reference" "C3884"
			(at 0 0 90)
			(layer "F.SilkS")
			(hide yes)
			(effects
				(font
					(size 1.27 1.27)
				)
			)
		)
		(property "Value" ""
			(at 0 0 90)
			(layer "F.Fab")
			(effects
				(font
					(size 1.27 1.27)
				)
			)
		)
		(duplicate_pad_numbers_are_jumpers no)
		(fp_line
			(start 0.7874 -0.4064)
			(end 0.7874 0.4064)
			(stroke
				(width 0.1524)
				(type default)
			)
			(layer "F.SilkS")
		)
		(fp_line
			(start -0.7874 -0.4064)
			(end 0.7874 -0.4064)
			(stroke
				(width 0.1524)
				(type default)
			)
			(layer "F.SilkS")
		)
		(fp_line
			(start 0.7874 0.4064)
			(end -0.7874 0.4064)
			(stroke
				(width 0.1524)
				(type default)
			)
			(layer "F.SilkS")
		)
		(fp_line
			(start -0.7874 0.4064)
			(end -0.7874 -0.4064)
			(stroke
				(width 0.1524)
				(type default)
			)
			(layer "F.SilkS")
		)
		(fp_line
			(start -0.12065 -0.305054)
			(end -0.12065 -0.2794)
			(stroke
				(width 0.1)
				(type default)
			)
			(layer "F.Fab")
		)
		(fp_line
			(start -0.67945 -0.305054)
			(end -0.12065 -0.305054)
			(stroke
				(width 0.1)
				(type default)
			)
			(layer "F.Fab")
		)
		(fp_line
			(start 0.67945 -0.3048)
			(end 0.67945 0.3048)
			(stroke
				(width 0.1)
				(type default)
			)
			(layer "F.Fab")
		)
		(fp_line
			(start 0.12065 -0.3048)
			(end 0.67945 -0.3048)
			(stroke
				(width 0.1)
				(type default)
			)
			(layer "F.Fab")
		)
		(fp_line
			(start 0.12065 -0.2794)
			(end 0.12065 -0.3048)
			(stroke
				(width 0.1)
				(type default)
			)
			(layer "F.Fab")
		)
		(fp_line
			(start -0.12065 -0.2794)
			(end 0.12065 -0.2794)
			(stroke
				(width 0.1)
				(type default)
			)
			(layer "F.Fab")
		)
		(fp_line
			(start 0.120396 0.2794)
			(end -0.12065 0.2794)
			(stroke
				(width 0.1)
				(type default)
			)
			(layer "F.Fab")
		)
		(fp_line
			(start -0.12065 0.2794)
			(end -0.12065 0.3048)
			(stroke
				(width 0.1)
				(type default)
			)
			(layer "F.Fab")
		)
		(fp_line
			(start 0.67945 0.3048)
			(end 0.120396 0.3048)
			(stroke
				(width 0.1)
				(type default)
			)
			(layer "F.Fab")
		)
		(fp_line
			(start 0.120396 0.3048)
			(end 0.120396 0.2794)
			(stroke
				(width 0.1)
				(type default)
			)
			(layer "F.Fab")
		)
		(fp_line
			(start -0.12065 0.3048)
			(end -0.67945 0.3048)
			(stroke
				(width 0.1)
				(type default)
			)
			(layer "F.Fab")
		)
		(fp_line
			(start -0.67945 0.3048)
			(end -0.67945 -0.305054)
			(stroke
				(width 0.1)
				(type default)
			)
			(layer "F.Fab")
		)
		(pad "1" smd circle
			(at -0.40005 0 90)
			(size 0 0)
			(layers "F.Cu" "F.Mask" "F.Paste")
			(net "P12V_SSD1")
		)
		(pad "2" smd circle
			(at 0.40005 0 90)
			(size 0 0)
			(layers "F.Cu" "F.Mask" "F.Paste")
			(net "GND")
		)
	)
	(footprint ""
		(layer "F.Cu")
		(at 200.675748 -36.915598 -90)
		(property "Reference" "R5562"
			(at 0 0 270)
			(layer "F.SilkS")
			(hide yes)
			(effects
				(font
					(size 1.27 1.27)
				)
			)
		)
		(property "Value" ""
			(at 0 0 270)
			(layer "F.Fab")
			(effects
				(font
					(size 1.27 1.27)
				)
			)
		)
		(duplicate_pad_numbers_are_jumpers no)
		(fp_line
			(start -0.7874 0.4064)
			(end -0.7874 -0.4064)
			(stroke
				(width 0.1524)
				(type default)
			)
			(layer "F.SilkS")
		)
		(fp_line
			(start 0.7874 0.4064)
			(end -0.7874 0.4064)
			(stroke
				(width 0.1524)
				(type default)
			)
			(layer "F.SilkS")
		)
		(fp_line
			(start -0.7874 -0.4064)
			(end 0.7874 -0.4064)
			(stroke
				(width 0.1524)
				(type default)
			)
			(layer "F.SilkS")
		)
		(fp_line
			(start 0.7874 -0.4064)
			(end 0.7874 0.4064)
			(stroke
				(width 0.1524)
				(type default)
			)
			(layer "F.SilkS")
		)
		(fp_line
			(start -0.67945 0.3048)
			(end -0.67945 -0.305054)
			(stroke
				(width 0.1)
				(type default)
			)
			(layer "F.Fab")
		)
		(fp_line
			(start -0.12065 0.3048)
			(end -0.67945 0.3048)
			(stroke
				(width 0.1)
				(type default)
			)
			(layer "F.Fab")
		)
		(fp_line
			(start 0.120396 0.3048)
			(end 0.120396 0.2794)
			(stroke
				(width 0.1)
				(type default)
			)
			(layer "F.Fab")
		)
		(fp_line
			(start 0.67945 0.3048)
			(end 0.120396 0.3048)
			(stroke
				(width 0.1)
				(type default)
			)
			(layer "F.Fab")
		)
		(fp_line
			(start -0.12065 0.2794)
			(end -0.12065 0.3048)
			(stroke
				(width 0.1)
				(type default)
			)
			(layer "F.Fab")
		)
		(fp_line
			(start 0.120396 0.2794)
			(end -0.12065 0.2794)
			(stroke
				(width 0.1)
				(type default)
			)
			(layer "F.Fab")
		)
		(fp_line
			(start -0.12065 -0.2794)
			(end 0.12065 -0.2794)
			(stroke
				(width 0.1)
				(type default)
			)
			(layer "F.Fab")
		)
		(fp_line
			(start 0.12065 -0.2794)
			(end 0.12065 -0.3048)
			(stroke
				(width 0.1)
				(type default)
			)
			(layer "F.Fab")
		)
		(fp_line
			(start 0.12065 -0.3048)
			(end 0.67945 -0.3048)
			(stroke
				(width 0.1)
				(type default)
			)
			(layer "F.Fab")
		)
		(fp_line
			(start 0.67945 -0.3048)
			(end 0.67945 0.3048)
			(stroke
				(width 0.1)
				(type default)
			)
			(layer "F.Fab")
		)
		(fp_line
			(start -0.67945 -0.305054)
			(end -0.12065 -0.305054)
			(stroke
				(width 0.1)
				(type default)
			)
			(layer "F.Fab")
		)
		(fp_line
			(start -0.12065 -0.305054)
			(end -0.12065 -0.2794)
			(stroke
				(width 0.1)
				(type default)
			)
			(layer "F.Fab")
		)
		(pad "1" smd circle
			(at -0.40005 0 270)
			(size 0 0)
			(layers "F.Cu" "F.Mask" "F.Paste")
			(net "PRSNT_SSD7_R1_N")
		)
		(pad "2" smd circle
			(at 0.40005 0 270)
			(size 0 0)
			(layers "F.Cu" "F.Mask" "F.Paste")
			(net "PRSNT_SSD7_R_N")
		)
	)
	(footprint ""
		(layer "F.Cu")
		(at 378.172218 -32.848042 90)
		(property "Reference" "PC965"
			(at 0 0 90)
			(layer "F.SilkS")
			(hide yes)
			(effects
				(font
					(size 1.27 1.27)
				)
			)
		)
		(property "Value" ""
			(at 0 0 90)
			(layer "F.Fab")
			(effects
				(font
					(size 1.27 1.27)
				)
			)
		)
		(duplicate_pad_numbers_are_jumpers no)
		(fp_line
			(start 0.7874 -0.4064)
			(end 0.7874 0.4064)
			(stroke
				(width 0.1524)
				(type default)
			)
			(layer "F.SilkS")
		)
		(fp_line
			(start -0.7874 -0.4064)
			(end 0.7874 -0.4064)
			(stroke
				(width 0.1524)
				(type default)
			)
			(layer "F.SilkS")
		)
		(fp_line
			(start 0.7874 0.4064)
			(end -0.7874 0.4064)
			(stroke
				(width 0.1524)
				(type default)
			)
			(layer "F.SilkS")
		)
		(fp_line
			(start -0.7874 0.4064)
			(end -0.7874 -0.4064)
			(stroke
				(width 0.1524)
				(type default)
			)
			(layer "F.SilkS")
		)
		(fp_line
			(start -0.12065 -0.305054)
			(end -0.12065 -0.2794)
			(stroke
				(width 0.1)
				(type default)
			)
			(layer "F.Fab")
		)
		(fp_line
			(start -0.67945 -0.305054)
			(end -0.12065 -0.305054)
			(stroke
				(width 0.1)
				(type default)
			)
			(layer "F.Fab")
		)
		(fp_line
			(start 0.67945 -0.3048)
			(end 0.67945 0.3048)
			(stroke
				(width 0.1)
				(type default)
			)
			(layer "F.Fab")
		)
		(fp_line
			(start 0.12065 -0.3048)
			(end 0.67945 -0.3048)
			(stroke
				(width 0.1)
				(type default)
			)
			(layer "F.Fab")
		)
		(fp_line
			(start 0.12065 -0.2794)
			(end 0.12065 -0.3048)
			(stroke
				(width 0.1)
				(type default)
			)
			(layer "F.Fab")
		)
		(fp_line
			(start -0.12065 -0.2794)
			(end 0.12065 -0.2794)
			(stroke
				(width 0.1)
				(type default)
			)
			(layer "F.Fab")
		)
		(fp_line
			(start 0.120396 0.2794)
			(end -0.12065 0.2794)
			(stroke
				(width 0.1)
				(type default)
			)
			(layer "F.Fab")
		)
		(fp_line
			(start -0.12065 0.2794)
			(end -0.12065 0.3048)
			(stroke
				(width 0.1)
				(type default)
			)
			(layer "F.Fab")
		)
		(fp_line
			(start 0.67945 0.3048)
			(end 0.120396 0.3048)
			(stroke
				(width 0.1)
				(type default)
			)
			(layer "F.Fab")
		)
		(fp_line
			(start 0.120396 0.3048)
			(end 0.120396 0.2794)
			(stroke
				(width 0.1)
				(type default)
			)
			(layer "F.Fab")
		)
		(fp_line
			(start -0.12065 0.3048)
			(end -0.67945 0.3048)
			(stroke
				(width 0.1)
				(type default)
			)
			(layer "F.Fab")
		)
		(fp_line
			(start -0.67945 0.3048)
			(end -0.67945 -0.305054)
			(stroke
				(width 0.1)
				(type default)
			)
			(layer "F.Fab")
		)
		(pad "1" smd circle
			(at -0.40005 0 90)
			(size 0 0)
			(layers "F.Cu" "F.Mask" "F.Paste")
			(net "P3V3_SSD13_CO_GATE")
		)
		(pad "2" smd circle
			(at 0.40005 0 90)
			(size 0 0)
			(layers "F.Cu" "F.Mask" "F.Paste")
			(net "GND")
		)
	)
	(footprint ""
		(layer "F.Cu")
		(at 265.686286 -252.356874 -90)
		(property "Reference" "R1353"
			(at 0 0 270)
			(layer "F.SilkS")
			(hide yes)
			(effects
				(font
					(size 1.27 1.27)
				)
			)
		)
		(property "Value" ""
			(at 0 0 270)
			(layer "F.Fab")
			(effects
				(font
					(size 1.27 1.27)
				)
			)
		)
		(duplicate_pad_numbers_are_jumpers no)
		(fp_line
			(start -0.7874 0.4064)
			(end -0.7874 -0.4064)
			(stroke
				(width 0.1524)
				(type default)
			)
			(layer "F.SilkS")
		)
		(fp_line
			(start 0.7874 0.4064)
			(end -0.7874 0.4064)
			(stroke
				(width 0.1524)
				(type default)
			)
			(layer "F.SilkS")
		)
		(fp_line
			(start -0.7874 -0.4064)
			(end 0.7874 -0.4064)
			(stroke
				(width 0.1524)
				(type default)
			)
			(layer "F.SilkS")
		)
		(fp_line
			(start 0.7874 -0.4064)
			(end 0.7874 0.4064)
			(stroke
				(width 0.1524)
				(type default)
			)
			(layer "F.SilkS")
		)
		(fp_line
			(start -0.67945 0.3048)
			(end -0.67945 -0.305054)
			(stroke
				(width 0.1)
				(type default)
			)
			(layer "F.Fab")
		)
		(fp_line
			(start -0.12065 0.3048)
			(end -0.67945 0.3048)
			(stroke
				(width 0.1)
				(type default)
			)
			(layer "F.Fab")
		)
		(fp_line
			(start 0.120396 0.3048)
			(end 0.120396 0.2794)
			(stroke
				(width 0.1)
				(type default)
			)
			(layer "F.Fab")
		)
		(fp_line
			(start 0.67945 0.3048)
			(end 0.120396 0.3048)
			(stroke
				(width 0.1)
				(type default)
			)
			(layer "F.Fab")
		)
		(fp_line
			(start -0.12065 0.2794)
			(end -0.12065 0.3048)
			(stroke
				(width 0.1)
				(type default)
			)
			(layer "F.Fab")
		)
		(fp_line
			(start 0.120396 0.2794)
			(end -0.12065 0.2794)
			(stroke
				(width 0.1)
				(type default)
			)
			(layer "F.Fab")
		)
		(fp_line
			(start -0.12065 -0.2794)
			(end 0.12065 -0.2794)
			(stroke
				(width 0.1)
				(type default)
			)
			(layer "F.Fab")
		)
		(fp_line
			(start 0.12065 -0.2794)
			(end 0.12065 -0.3048)
			(stroke
				(width 0.1)
				(type default)
			)
			(layer "F.Fab")
		)
		(fp_line
			(start 0.12065 -0.3048)
			(end 0.67945 -0.3048)
			(stroke
				(width 0.1)
				(type default)
			)
			(layer "F.Fab")
		)
		(fp_line
			(start 0.67945 -0.3048)
			(end 0.67945 0.3048)
			(stroke
				(width 0.1)
				(type default)
			)
			(layer "F.Fab")
		)
		(fp_line
			(start -0.67945 -0.305054)
			(end -0.12065 -0.305054)
			(stroke
				(width 0.1)
				(type default)
			)
			(layer "F.Fab")
		)
		(fp_line
			(start -0.12065 -0.305054)
			(end -0.12065 -0.2794)
			(stroke
				(width 0.1)
				(type default)
			)
			(layer "F.Fab")
		)
		(pad "1" smd circle
			(at -0.40005 0 270)
			(size 0 0)
			(layers "F.Cu" "F.Mask" "F.Paste")
			(net "GND")
		)
		(pad "2" smd circle
			(at 0.40005 0 270)
			(size 0 0)
			(layers "F.Cu" "F.Mask" "F.Paste")
			(net "PEX2_DBG_MODE2")
		)
	)
	(footprint ""
		(layer "F.Cu")
		(at 446.131188 -415.621216 90)
		(property "Reference" "R5605"
			(at 0 0 90)
			(layer "F.SilkS")
			(hide yes)
			(effects
				(font
					(size 1.27 1.27)
				)
			)
		)
		(property "Value" ""
			(at 0 0 90)
			(layer "F.Fab")
			(effects
				(font
					(size 1.27 1.27)
				)
			)
		)
		(duplicate_pad_numbers_are_jumpers no)
		(fp_line
			(start 0.7874 -0.4064)
			(end 0.7874 0.4064)
			(stroke
				(width 0.1524)
				(type default)
			)
			(layer "F.SilkS")
		)
		(fp_line
			(start -0.7874 -0.4064)
			(end 0.7874 -0.4064)
			(stroke
				(width 0.1524)
				(type default)
			)
			(layer "F.SilkS")
		)
		(fp_line
			(start 0.7874 0.4064)
			(end -0.7874 0.4064)
			(stroke
				(width 0.1524)
				(type default)
			)
			(layer "F.SilkS")
		)
		(fp_line
			(start -0.7874 0.4064)
			(end -0.7874 -0.4064)
			(stroke
				(width 0.1524)
				(type default)
			)
			(layer "F.SilkS")
		)
		(fp_line
			(start -0.12065 -0.305054)
			(end -0.12065 -0.2794)
			(stroke
				(width 0.1)
				(type default)
			)
			(layer "F.Fab")
		)
		(fp_line
			(start -0.67945 -0.305054)
			(end -0.12065 -0.305054)
			(stroke
				(width 0.1)
				(type default)
			)
			(layer "F.Fab")
		)
		(fp_line
			(start 0.67945 -0.3048)
			(end 0.67945 0.3048)
			(stroke
				(width 0.1)
				(type default)
			)
			(layer "F.Fab")
		)
		(fp_line
			(start 0.12065 -0.3048)
			(end 0.67945 -0.3048)
			(stroke
				(width 0.1)
				(type default)
			)
			(layer "F.Fab")
		)
		(fp_line
			(start 0.12065 -0.2794)
			(end 0.12065 -0.3048)
			(stroke
				(width 0.1)
				(type default)
			)
			(layer "F.Fab")
		)
		(fp_line
			(start -0.12065 -0.2794)
			(end 0.12065 -0.2794)
			(stroke
				(width 0.1)
				(type default)
			)
			(layer "F.Fab")
		)
		(fp_line
			(start 0.120396 0.2794)
			(end -0.12065 0.2794)
			(stroke
				(width 0.1)
				(type default)
			)
			(layer "F.Fab")
		)
		(fp_line
			(start -0.12065 0.2794)
			(end -0.12065 0.3048)
			(stroke
				(width 0.1)
				(type default)
			)
			(layer "F.Fab")
		)
		(fp_line
			(start 0.67945 0.3048)
			(end 0.120396 0.3048)
			(stroke
				(width 0.1)
				(type default)
			)
			(layer "F.Fab")
		)
		(fp_line
			(start 0.120396 0.3048)
			(end 0.120396 0.2794)
			(stroke
				(width 0.1)
				(type default)
			)
			(layer "F.Fab")
		)
		(fp_line
			(start -0.12065 0.3048)
			(end -0.67945 0.3048)
			(stroke
				(width 0.1)
				(type default)
			)
			(layer "F.Fab")
		)
		(fp_line
			(start -0.67945 0.3048)
			(end -0.67945 -0.305054)
			(stroke
				(width 0.1)
				(type default)
			)
			(layer "F.Fab")
		)
		(pad "1" smd circle
			(at -0.40005 0 90)
			(size 0 0)
			(layers "F.Cu" "F.Mask" "F.Paste")
			(net "LM75_1_A0")
		)
		(pad "2" smd circle
			(at 0.40005 0 90)
			(size 0 0)
			(layers "F.Cu" "F.Mask" "F.Paste")
			(net "GND")
		)
	)
	(footprint ""
		(layer "F.Cu")
		(at 214.534496 -30.94609 180)
		(property "Reference" "C304"
			(at 0 0 180)
			(layer "F.SilkS")
			(hide yes)
			(effects
				(font
					(size 1.27 1.27)
				)
			)
		)
		(property "Value" ""
			(at 0 0 180)
			(layer "F.Fab")
			(effects
				(font
					(size 1.27 1.27)
				)
			)
		)
		(duplicate_pad_numbers_are_jumpers no)
		(fp_line
			(start 0.299974 0.150114)
			(end -0.299974 0.150114)
			(stroke
				(width 0.1)
				(type default)
			)
			(layer "F.Fab")
		)
		(fp_line
			(start 0.299974 -0.150114)
			(end 0.299974 0.150114)
			(stroke
				(width 0.1)
				(type default)
			)
			(layer "F.Fab")
		)
		(fp_line
			(start -0.299974 0.150114)
			(end -0.299974 -0.150114)
			(stroke
				(width 0.1)
				(type default)
			)
			(layer "F.Fab")
		)
		(fp_line
			(start -0.299974 -0.150114)
			(end 0.299974 -0.150114)
			(stroke
				(width 0.1)
				(type default)
			)
			(layer "F.Fab")
		)
		(pad "1" smd rect
			(at -0.2667 0 180)
			(size 0.3048 0.381)
			(layers "F.Cu" "F.Mask" "F.Paste")
			(net "P5E_PEX1_STN2_TX_DP<33>")
		)
		(pad "2" smd rect
			(at 0.2667 0 180)
			(size 0.3048 0.381)
			(layers "F.Cu" "F.Mask" "F.Paste")
			(net "P5E_PEX1_STN2_TX_C_DP<33>")
		)
	)
	(footprint ""
		(layer "F.Cu")
		(at 6.709156 -26.03373)
		(property "Reference" "R4055"
			(at 0 0 0)
			(layer "F.SilkS")
			(hide yes)
			(effects
				(font
					(size 1.27 1.27)
				)
			)
		)
		(property "Value" ""
			(at 0 0 0)
			(layer "F.Fab")
			(effects
				(font
					(size 1.27 1.27)
				)
			)
		)
		(duplicate_pad_numbers_are_jumpers no)
		(fp_line
			(start -0.7874 -0.4064)
			(end 0.7874 -0.4064)
			(stroke
				(width 0.1524)
				(type default)
			)
			(layer "F.SilkS")
		)
		(fp_line
			(start -0.7874 0.4064)
			(end -0.7874 -0.4064)
			(stroke
				(width 0.1524)
				(type default)
			)
			(layer "F.SilkS")
		)
		(fp_line
			(start 0.7874 -0.4064)
			(end 0.7874 0.4064)
			(stroke
				(width 0.1524)
				(type default)
			)
			(layer "F.SilkS")
		)
		(fp_line
			(start 0.7874 0.4064)
			(end -0.7874 0.4064)
			(stroke
				(width 0.1524)
				(type default)
			)
			(layer "F.SilkS")
		)
		(fp_line
			(start -0.67945 -0.305054)
			(end -0.12065 -0.305054)
			(stroke
				(width 0.1)
				(type default)
			)
			(layer "F.Fab")
		)
		(fp_line
			(start -0.67945 0.3048)
			(end -0.67945 -0.305054)
			(stroke
				(width 0.1)
				(type default)
			)
			(layer "F.Fab")
		)
		(fp_line
			(start -0.12065 -0.305054)
			(end -0.12065 -0.2794)
			(stroke
				(width 0.1)
				(type default)
			)
			(layer "F.Fab")
		)
		(fp_line
			(start -0.12065 -0.2794)
			(end 0.12065 -0.2794)
			(stroke
				(width 0.1)
				(type default)
			)
			(layer "F.Fab")
		)
		(fp_line
			(start -0.12065 0.2794)
			(end -0.12065 0.3048)
			(stroke
				(width 0.1)
				(type default)
			)
			(layer "F.Fab")
		)
		(fp_line
			(start -0.12065 0.3048)
			(end -0.67945 0.3048)
			(stroke
				(width 0.1)
				(type default)
			)
			(layer "F.Fab")
		)
		(fp_line
			(start 0.120396 0.2794)
			(end -0.12065 0.2794)
			(stroke
				(width 0.1)
				(type default)
			)
			(layer "F.Fab")
		)
		(fp_line
			(start 0.120396 0.3048)
			(end 0.120396 0.2794)
			(stroke
				(width 0.1)
				(type default)
			)
			(layer "F.Fab")
		)
		(fp_line
			(start 0.12065 -0.3048)
			(end 0.67945 -0.3048)
			(stroke
				(width 0.1)
				(type default)
			)
			(layer "F.Fab")
		)
		(fp_line
			(start 0.12065 -0.2794)
			(end 0.12065 -0.3048)
			(stroke
				(width 0.1)
				(type default)
			)
			(layer "F.Fab")
		)
		(fp_line
			(start 0.67945 -0.3048)
			(end 0.67945 0.3048)
			(stroke
				(width 0.1)
				(type default)
			)
			(layer "F.Fab")
		)
		(fp_line
			(start 0.67945 0.3048)
			(end 0.120396 0.3048)
			(stroke
				(width 0.1)
				(type default)
			)
			(layer "F.Fab")
		)
		(pad "1" smd circle
			(at -0.40005 0)
			(size 0 0)
			(layers "F.Cu" "F.Mask" "F.Paste")
			(net "P3V3_AUX")
		)
		(pad "2" smd circle
			(at 0.40005 0)
			(size 0 0)
			(layers "F.Cu" "F.Mask" "F.Paste")
			(net "PRSNT_SSD0_R_N")
		)
	)
)
